# TIMECARD (Time Appliance Project (Time Card)) — schematic netlist excerpt (pin names and nets, part order shuffled) for the footprints in the layout excerpt that follows; sources: Cadence DE-HDL packaged netlist, KiCad conversion of R4006-B0001-02_R01.brd

C11  CAPACITOR  100PF 50V 10%  pkg SMC_0201R  page 32 : \1\ = UNNAMED_516_CAPACITOR_I29_1 ; \2\ = XP5R0V_FB_R_TO_AGND
CR1  DIODE_2F  pkg SMC_CR_067X049_V1  page 33 : A = XP5R0V ; C = UNNAMED_525_CAPACITOR_I7_1

(kicad_pcb
	(version 20260206)
	(generator "pcbnew")
	(generator_version "10.0")
	(general
		(thickness 1.6)
		(legacy_teardrops no)
	)
	(paper "A4")
	(title_block
		(title "timecard-production-celestica-r4006 — R4006-B0001-02_R01.brd")
		(comment 1 "Time Appliance Project (Time Card) / footprints 440-441 of 1113")
	)
	(layers
		(0 "F.Cu" signal "TOP")
		(4 "In1.Cu" signal "L02_GND1")
		(6 "In2.Cu" signal "L03_SIG1")
		(8 "In3.Cu" signal "L04_GND2")
		(10 "In4.Cu" signal "L05_VCC1")
		(12 "In5.Cu" signal "L06_VCC2")
		(14 "In6.Cu" signal "L07_GND3")
		(16 "In7.Cu" signal "L08_SIG2")
		(18 "In8.Cu" signal "L09_GND4")
		(2 "B.Cu" signal "BOTTOM")
		(9 "F.Adhes" user "F.Adhesive")
		(11 "B.Adhes" user "B.Adhesive")
		(13 "F.Paste" user "Package Geometry/Pastemask Top")
		(15 "B.Paste" user "Package Geometry/Pastemask Bottom")
		(5 "F.SilkS" user "Ref Des/Silkscreen Top")
		(7 "B.SilkS" user "Ref Des/Silkscreen Bottom")
		(1 "F.Mask" user "Board Geometry/Soldermask Top")
		(3 "B.Mask" user "Board Geometry/Soldermask Bottom")
		(17 "Dwgs.User" user "User.Drawings")
		(19 "Cmts.User" user "User.Comments")
		(21 "Eco1.User" user "User.Eco1")
		(23 "Eco2.User" user "User.Eco2")
		(25 "Edge.Cuts" user "Board Geometry/Outline")
		(27 "Margin" user)
		(31 "F.CrtYd" user "Package Geometry/Place Bound Top")
		(29 "B.CrtYd" user "Package Geometry/Place Bound Bottom")
		(35 "F.Fab" user "Ref Des/Assembly Top")
		(33 "B.Fab" user "Ref Des/Assembly Bottom")
	)
	(footprint ""
		(layer "F.Cu")
		(at 41.656 -83.058 180)
		(property "Reference" "CR1"
			(at 0.635 3.00863 0)
			(unlocked yes)
			(layer "F.SilkS")
			(effects
				(font
					(size 0.7874 0.5842)
					(thickness 0.1524)
				)
			)
		)
		(property "Value" ""
			(at 0 0 180)
			(layer "F.Fab")
			(effects
				(font
					(size 1.27 1.27)
				)
			)
		)
		(property "Device Type" "DIODE_2F-G122-10186-01"
			(at 0 2.037842 180)
			(unlocked yes)
			(layer "F.Fab")
			(hide yes)
			(effects
				(font
					(size 0.7874 0.5842)
					(thickness 0.000001)
				)
			)
		)
		(property "User Part Number" "PARTNUM*"
			(at 0 3.231642 180)
			(unlocked yes)
			(layer "Cmts.User")
			(hide yes)
			(effects
				(font
					(size 0.7874 0.5842)
					(thickness 0.000001)
				)
			)
		)
		(duplicate_pad_numbers_are_jumpers no)
		(fp_line
			(start 1.608074 0.928878)
			(end -1.608074 0.928878)
			(stroke
				(width 0.1)
				(type default)
			)
			(layer "F.SilkS")
		)
		(fp_line
			(start 1.608074 -0.928878)
			(end 1.608074 0.928878)
			(stroke
				(width 0.1)
				(type default)
			)
			(layer "F.SilkS")
		)
		(fp_line
			(start -1.608074 0.928878)
			(end -1.608074 -0.928878)
			(stroke
				(width 0.1)
				(type default)
			)
			(layer "F.SilkS")
		)
		(fp_line
			(start -1.608074 -0.928878)
			(end 1.608074 -0.928878)
			(stroke
				(width 0.1)
				(type default)
			)
			(layer "F.SilkS")
		)
		(fp_poly
			(pts
				(xy -2.116074 -0.928878) (xy -2.116074 0.928878) (xy -1.608074 0.928878) (xy -1.608074 -0.928878)
			)
			(stroke
				(width 0)
				(type default)
			)
			(fill yes)
			(layer "F.SilkS")
		)
		(fp_poly
			(pts
				(xy -2.116074 1.182878) (xy 1.862074 1.182878) (xy 1.862074 -1.182878) (xy -2.116074 -1.182878)
			)
			(stroke
				(width 0)
				(type default)
			)
			(fill no)
			(layer "F.CrtYd")
		)
		(fp_line
			(start 0.899922 0.674878)
			(end -0.899922 0.674878)
			(stroke
				(width 0.1)
				(type default)
			)
			(layer "F.Fab")
		)
		(fp_line
			(start 0.899922 -0.674878)
			(end 0.899922 0.674878)
			(stroke
				(width 0.1)
				(type default)
			)
			(layer "F.Fab")
		)
		(fp_line
			(start -0.899922 0.674878)
			(end -0.899922 -0.674878)
			(stroke
				(width 0.1)
				(type default)
			)
			(layer "F.Fab")
		)
		(fp_line
			(start -0.899922 -0.674878)
			(end 0.899922 -0.674878)
			(stroke
				(width 0.1)
				(type default)
			)
			(layer "F.Fab")
		)
		(fp_poly
			(pts
				(xy -0.899922 -0.674878) (xy -0.899922 0.674878) (xy -0.391922 0.674878) (xy -0.391922 -0.674878)
			)
			(stroke
				(width 0)
				(type default)
			)
			(fill yes)
			(layer "F.Fab")
		)
		(fp_text user "A"
			(at 2.54 1.10363 0)
			(unlocked yes)
			(layer "F.SilkS")
			(effects
				(font
					(size 0.7874 0.5842)
					(thickness 0.1524)
				)
			)
		)
		(fp_text user "C"
			(at -2.413 0.78105 0)
			(unlocked yes)
			(layer "F.SilkS")
			(effects
				(font
					(size 0.635 0.4064)
					(thickness 0.1524)
				)
			)
		)
		(fp_text user "A"
			(at 2.262124 0.156718 0)
			(unlocked yes)
			(layer "F.Fab")
			(effects
				(font
					(size 0.7874 0.5842)
					(thickness 0.1524)
				)
			)
		)
		(fp_text user "C"
			(at -1.905 1.10363 0)
			(unlocked yes)
			(layer "F.Fab")
			(effects
				(font
					(size 0.7874 0.5842)
					(thickness 0.1524)
				)
			)
		)
		(pad "A" smd rect
			(at 1.100074 0 180)
			(size 0.508 0.508)
			(layers "F.Cu" "F.Mask" "F.Paste")
			(net "XP5R0V")
		)
		(pad "C" smd rect
			(at -1.100074 0 180)
			(size 0.508 0.508)
			(layers "F.Cu" "F.Mask" "F.Paste")
			(net "UNNAMED_525_CAPACITOR_I7_1")
		)
	)
	(footprint ""
		(layer "F.Cu")
		(at 36.9824 -103.7844)
		(property "Reference" "C11"
			(at -4.0894 -1.33223 0)
			(unlocked yes)
			(layer "F.SilkS")
			(effects
				(font
					(size 0.7874 0.5842)
					(thickness 0.1524)
				)
			)
		)
		(property "Value" "VAL*"
			(at 0.193548 2.13614 0)
			(unlocked yes)
			(layer "F.Fab")
			(hide yes)
			(effects
				(font
					(size 0.7874 0.5842)
					(thickness 0.1524)
				)
			)
		)
		(property "Tolerance" "TOL*"
			(at 0.216154 3.1496 0)
			(unlocked yes)
			(layer "Cmts.User")
			(hide yes)
			(effects
				(font
					(size 0.7874 0.5842)
					(thickness 0.1524)
				)
			)
		)
		(property "Device Type" "CAPACITOR-G104-0B101-FK,100PF,A"
			(at 0.184404 1.180592 0)
			(unlocked yes)
			(layer "F.Fab")
			(hide yes)
			(effects
				(font
					(size 0.7874 0.5842)
					(thickness 0.1524)
				)
			)
		)
		(property "User Part Number" "PARTNUM*"
			(at 0.216154 4.185666 0)
			(unlocked yes)
			(layer "Cmts.User")
			(hide yes)
			(effects
				(font
					(size 0.7874 0.5842)
					(thickness 0.1524)
				)
			)
		)
		(duplicate_pad_numbers_are_jumpers no)
		(fp_line
			(start -0.671322 -0.4445)
			(end 0.671322 -0.4445)
			(stroke
				(width 0.1)
				(type default)
			)
			(layer "F.SilkS")
		)
		(fp_line
			(start -0.671322 0.4445)
			(end -0.671322 -0.4445)
			(stroke
				(width 0.1)
				(type default)
			)
			(layer "F.SilkS")
		)
		(fp_line
			(start 0.671322 -0.4445)
			(end 0.671322 0.4445)
			(stroke
				(width 0.1)
				(type default)
			)
			(layer "F.SilkS")
		)
		(fp_line
			(start 0.671322 0.4445)
			(end -0.671322 0.4445)
			(stroke
				(width 0.1)
				(type default)
			)
			(layer "F.SilkS")
		)
		(fp_rect
			(start 0.671322 -0.4445)
			(end -0.671322 0.4445)
			(stroke
				(width 0)
				(type default)
			)
			(fill no)
			(layer "F.CrtYd")
		)
		(fp_line
			(start -0.31496 -0.1651)
			(end -0.31496 0.1651)
			(stroke
				(width 0.1)
				(type default)
			)
			(layer "F.Fab")
		)
		(fp_line
			(start -0.31496 0.1651)
			(end 0.31496 0.1651)
			(stroke
				(width 0.1)
				(type default)
			)
			(layer "F.Fab")
		)
		(fp_line
			(start 0.31496 -0.1651)
			(end -0.31496 -0.1651)
			(stroke
				(width 0.1)
				(type default)
			)
			(layer "F.Fab")
		)
		(fp_line
			(start 0.31496 0.1651)
			(end 0.31496 -0.1651)
			(stroke
				(width 0.1)
				(type default)
			)
			(layer "F.Fab")
		)
		(pad "1" smd rect
			(at -0.264922 0)
			(size 0.3048 0.381)
			(layers "F.Cu" "F.Mask" "F.Paste")
			(net "UNNAMED_516_CAPACITOR_I29_1")
		)
		(pad "2" smd rect
			(at 0.264922 0)
			(size 0.3048 0.381)
			(layers "F.Cu" "F.Mask" "F.Paste")
			(net "XP5R0V_FB_R_TO_AGND")
		)
		(zone
			(layer "F.Cu")
			(hatch none 0.5)
			(connect_pads
				(clearance 0)
			)
			(min_thickness 0.25)
			(keepout
				(tracks allowed)
				(vias not_allowed)
				(pads allowed)
				(copperpour not_allowed)
				(footprints allowed)
			)
			(placement
				(enabled no)
				(sheetname "")
			)
			(fill
				(thermal_gap 0.5)
				(thermal_bridge_width 0.5)
				(island_removal_mode 0)
			)
			(polygon
				(pts
					(xy 37.094922 -103.9749) (xy 36.869878 -103.9749) (xy 36.869878 -103.5939) (xy 37.094922 -103.5939)
				)
			)
		)
	)
)
